FILE_TYPE = MACRO_DRAWING;
SET COLOR_WIRE YELLOW;
SET COLOR_PROP ORANGE;
SET COLOR_DOT WHITE;
SET COLOR_ARC YELLOW;
SET COLOR_BODY GREEN;
SET COLOR_NOTE PURPLE;
SET PROP_DISPLAY VALUE;
SET PAGE_NUMBER P166;
FORCEADD UNIVERSAL_GND..1
(-1975 -650);
FORCEPROP 3 LASTPIN (-1975 -600) SIG_NAME GND\g
J 0
(-1965 -590);
DISPLAY 0.659574 (-1965 -590);
PAINT MONO (-1965 -590);
DISPLAY INVISIBLE (-1965 -590);
FORCEPROP 1 LAST HDL_POWER GND
J 1
(-1950 -725);
DISPLAY 0.872340 (-1950 -725);
PAINT GREEN (-1950 -725);
DISPLAY INVISIBLE (-1950 -725);
FORCEPROP 1 LAST PATH I10
J 0
(-1900 -650);
DISPLAY 0.872340 (-1900 -650);
PAINT AQUA (-1900 -650);
DISPLAY INVISIBLE (-1900 -650);
FORCEPROP 2 LAST CDS_LIB pure_quanta_power
J 0
(-1975 -650);
DISPLAY INVISIBLE (-1975 -650);
FORCEADD UNIVERSAL_GND..1
(-1575 -650);
FORCEPROP 3 LASTPIN (-1575 -600) SIG_NAME GND\g
J 0
(-1565 -590);
DISPLAY 0.659574 (-1565 -590);
PAINT MONO (-1565 -590);
DISPLAY INVISIBLE (-1565 -590);
FORCEPROP 1 LAST HDL_POWER GND
J 1
(-1550 -725);
DISPLAY 0.872340 (-1550 -725);
PAINT GREEN (-1550 -725);
DISPLAY INVISIBLE (-1550 -725);
FORCEPROP 1 LAST PATH I12
J 0
(-1500 -650);
DISPLAY 0.872340 (-1500 -650);
PAINT AQUA (-1500 -650);
DISPLAY INVISIBLE (-1500 -650);
FORCEPROP 2 LAST CDS_LIB pure_quanta_power
J 0
(-1575 -650);
DISPLAY INVISIBLE (-1575 -650);
FORCEADD UNIVERSAL_GND..1
(-1775 350);
FORCEPROP 3 LASTPIN (-1775 400) SIG_NAME GND\g
J 0
(-1765 410);
DISPLAY 0.659574 (-1765 410);
PAINT MONO (-1765 410);
DISPLAY INVISIBLE (-1765 410);
FORCEPROP 1 LAST HDL_POWER GND
J 1
(-1750 275);
DISPLAY 0.872340 (-1750 275);
PAINT GREEN (-1750 275);
DISPLAY INVISIBLE (-1750 275);
FORCEPROP 1 LAST PATH I14
J 0
(-1700 350);
DISPLAY 0.872340 (-1700 350);
PAINT AQUA (-1700 350);
DISPLAY INVISIBLE (-1700 350);
FORCEPROP 2 LAST CDS_LIB pure_quanta_power
J 0
(-1775 350);
DISPLAY INVISIBLE (-1775 350);
FORCEADD Q_CAP..1
(-1775 575);
FORCEPROP 1 LAST LOCATION C2
J 0
(-1725 675);
DISPLAY 0.489362 (-1725 675);
PAINT SKYBLUE (-1725 675);
FORCEPROP 0 LAST $SEC 1
J 0
(-1725 700);
DISPLAY 0.680851 (-1725 700);
PAINT MONO (-1725 700);
DISPLAY INVISIBLE (-1725 700);
FORCEPROP 0 LAST CDS_SEC 1
J 0
(-1725 700);
DISPLAY 1.021277 (-1725 700);
DISPLAY INVISIBLE (-1725 700);
FORCEPROP 1 LASTPIN (-1775 675) $PN 1
J 0
(-1765 655);
DISPLAY 0.489362 (-1765 655);
PAINT MONO (-1765 655);
FORCEPROP 1 LASTPIN (-1775 475) $PN 2
J 0
(-1765 455);
DISPLAY 0.489362 (-1765 455);
PAINT MONO (-1765 455);
FORCEPROP 1 LAST PACK_TYPE C0603
J 0
(-1725 375);
DISPLAY 0.489362 (-1725 375);
PAINT SKYBLUE (-1725 375);
FORCEPROP 1 LAST PART_NUMBER CH6103ME902
J 0
(-1725 425);
DISPLAY 0.489362 (-1725 425);
PAINT SKYBLUE (-1725 425);
FORCEPROP 1 LAST VOLTAGE 16V
J 0
(-1725 575);
DISPLAY 0.489362 (-1725 575);
PAINT SKYBLUE (-1725 575);
FORCEPROP 1 LAST MATERIAL X6S
J 0
(-1725 475);
DISPLAY 0.489362 (-1725 475);
PAINT SKYBLUE (-1725 475);
FORCEPROP 1 LAST TOLERANCE 20%
J 0
(-1725 525);
DISPLAY 0.489362 (-1725 525);
PAINT SKYBLUE (-1725 525);
FORCEPROP 1 LAST VALUE 10UF
J 0
(-1725 625);
DISPLAY 0.489362 (-1725 625);
PAINT SKYBLUE (-1725 625);
FORCEPROP 2 LAST CDS_LIB pure_quanta
J 0
(-1775 575);
DISPLAY INVISIBLE (-1775 575);
FORCEPROP 1 LAST PATH I15
J 0
(-1725 725);
DISPLAY 0.978723 (-1725 725);
PAINT WHITE (-1725 725);
DISPLAY INVISIBLE (-1725 725);
FORCEADD Q_CAP..1
(-850 -25);
FORCEPROP 1 LAST LOCATION C3
J 0
(-800 75);
DISPLAY 0.489362 (-800 75);
PAINT SKYBLUE (-800 75);
FORCEPROP 0 LAST $SEC 1
J 0
(-800 100);
DISPLAY 0.680851 (-800 100);
PAINT MONO (-800 100);
DISPLAY INVISIBLE (-800 100);
FORCEPROP 0 LAST CDS_SEC 1
J 0
(-800 100);
DISPLAY 1.021277 (-800 100);
DISPLAY INVISIBLE (-800 100);
FORCEPROP 1 LASTPIN (-850 75) $PN 1
J 0
(-840 55);
DISPLAY 0.489362 (-840 55);
PAINT MONO (-840 55);
FORCEPROP 1 LASTPIN (-850 -125) $PN 2
J 0
(-840 -145);
DISPLAY 0.489362 (-840 -145);
PAINT MONO (-840 -145);
FORCEPROP 1 LAST PACK_TYPE C0402
J 0
(-800 -225);
DISPLAY 0.489362 (-800 -225);
PAINT SKYBLUE (-800 -225);
FORCEPROP 1 LAST VOLTAGE 6.3V
J 0
(-800 -25);
DISPLAY 0.489362 (-800 -25);
PAINT SKYBLUE (-800 -25);
FORCEPROP 1 LAST PART_NUMBER CH6101MEB01
J 0
(-800 -175);
DISPLAY 0.489362 (-800 -175);
PAINT SKYBLUE (-800 -175);
FORCEPROP 1 LAST VALUE 10UF
J 0
(-800 25);
DISPLAY 0.489362 (-800 25);
PAINT SKYBLUE (-800 25);
FORCEPROP 1 LAST TOLERANCE 20%
J 0
(-800 -75);
DISPLAY 0.489362 (-800 -75);
PAINT SKYBLUE (-800 -75);
FORCEPROP 1 LAST MATERIAL X6S
J 0
(-800 -125);
DISPLAY 0.489362 (-800 -125);
PAINT SKYBLUE (-800 -125);
FORCEPROP 1 LAST PATH I16
J 0
(-800 125);
DISPLAY 0.978723 (-800 125);
PAINT WHITE (-800 125);
DISPLAY INVISIBLE (-800 125);
FORCEPROP 2 LAST CDS_LIB pure_quanta
J 0
(-850 -25);
DISPLAY INVISIBLE (-850 -25);
FORCEADD UNIVERSAL_GND..1
(-475 -400);
FORCEPROP 3 LASTPIN (-475 -350) SIG_NAME GND\g
J 0
(-465 -340);
DISPLAY 0.659574 (-465 -340);
PAINT MONO (-465 -340);
DISPLAY INVISIBLE (-465 -340);
FORCEPROP 1 LAST HDL_POWER GND
J 1
(-450 -475);
DISPLAY 0.872340 (-450 -475);
PAINT GREEN (-450 -475);
DISPLAY INVISIBLE (-450 -475);
FORCEPROP 1 LAST PATH I17
J 0
(-400 -400);
DISPLAY 0.872340 (-400 -400);
PAINT AQUA (-400 -400);
DISPLAY INVISIBLE (-400 -400);
FORCEPROP 2 LAST CDS_LIB pure_quanta_power
J 0
(-475 -400);
DISPLAY INVISIBLE (-475 -400);
FORCEADD Q_CAP..1
(-475 -25);
FORCEPROP 1 LAST LOCATION C58
J 0
(-425 75);
DISPLAY 0.489362 (-425 75);
PAINT SKYBLUE (-425 75);
FORCEPROP 0 LAST $SEC 1
J 0
(-425 100);
DISPLAY 0.680851 (-425 100);
PAINT MONO (-425 100);
DISPLAY INVISIBLE (-425 100);
FORCEPROP 0 LAST CDS_SEC 1
J 0
(-425 100);
DISPLAY 1.021277 (-425 100);
DISPLAY INVISIBLE (-425 100);
FORCEPROP 1 LASTPIN (-475 75) $PN 1
J 0
(-465 55);
DISPLAY 0.489362 (-465 55);
PAINT MONO (-465 55);
FORCEPROP 1 LASTPIN (-475 -125) $PN 2
J 0
(-465 -145);
DISPLAY 0.489362 (-465 -145);
PAINT MONO (-465 -145);
FORCEPROP 1 LAST PACK_TYPE 0402
J 0
(-425 -225);
DISPLAY 0.489362 (-425 -225);
PAINT SKYBLUE (-425 -225);
FORCEPROP 1 LAST VOLTAGE 25V
J 0
(-425 -25);
DISPLAY 0.489362 (-425 -25);
PAINT SKYBLUE (-425 -25);
FORCEPROP 1 LAST PART_NUMBER CH4104K1B00
J 0
(-425 -175);
DISPLAY 0.489362 (-425 -175);
PAINT SKYBLUE (-425 -175);
FORCEPROP 1 LAST VALUE 0.1UF
J 0
(-425 25);
DISPLAY 0.489362 (-425 25);
PAINT SKYBLUE (-425 25);
FORCEPROP 1 LAST TOLERANCE 10%
J 0
(-425 -75);
DISPLAY 0.489362 (-425 -75);
PAINT SKYBLUE (-425 -75);
FORCEPROP 1 LAST MATERIAL X7R
J 0
(-425 -125);
DISPLAY 0.489362 (-425 -125);
PAINT SKYBLUE (-425 -125);
FORCEPROP 1 LAST PATH I18
J 0
(-425 125);
DISPLAY 0.978723 (-425 125);
PAINT WHITE (-425 125);
DISPLAY INVISIBLE (-425 125);
FORCEPROP 2 LAST CDS_LIB pure_quanta
J 0
(-475 -25);
DISPLAY INVISIBLE (-475 -25);
FORCEADD VCC_CORE..1
(-475 250);
FORCEPROP 3 LASTPIN (-475 200) SIG_NAME P1V8_STBY\g
J 0
(-465 210);
DISPLAY 0.659574 (-465 210);
PAINT MONO (-465 210);
DISPLAY INVISIBLE (-465 210);
FORCEPROP 1 LAST HDL_POWER P1V8_STBY
J 1
(-475 300);
DISPLAY 0.489362 (-475 300);
PAINT GREEN (-475 300);
FORCEPROP 1 LAST PATH I19
J 0
(-425 275);
DISPLAY 0.872340 (-425 275);
PAINT AQUA (-425 275);
DISPLAY INVISIBLE (-425 275);
FORCEPROP 2 LAST CDS_LIB pure_quanta_power
J 0
(-475 250);
DISPLAY INVISIBLE (-475 250);
FORCEADD OFFPAGE..1
(-5350 100);
FORCEPROP 2 LAST $XR1 80 
J 0
(-5692 100);
DISPLAY 0.638298 (-5692 100);
PAINT MONO (-5692 100);
FORCEPROP 2 LAST $XR0 166 
J 0
(-5602 100);
DISPLAY 0.638298 (-5602 100);
PAINT MONO (-5602 100);
FORCEPROP 2 LAST PATH I2
J 0
(-5300 175);
DISPLAY 1.021277 (-5300 175);
DISPLAY INVISIBLE (-5300 175);
FORCEPROP 1 LAST COMMENT_BODY TRUE
J 0
(-5225 0);
DISPLAY 0.872340 (-5225 0);
PAINT GREEN (-5225 0);
DISPLAY INVISIBLE (-5225 0);
FORCEPROP 1 LAST OFFPAGE TRUE
J 0
(-5025 -25);
DISPLAY 0.872340 (-5025 -25);
PAINT GREEN (-5025 -25);
DISPLAY INVISIBLE (-5025 -25);
FORCEPROP 2 LAST CDS_LIB standard
J 0
(-5350 100);
DISPLAY INVISIBLE (-5350 100);
FORCEADD VCC_CORE..1
(-1775 900);
FORCEPROP 3 LASTPIN (-1775 850) SIG_NAME P3V3_STBY\g
J 0
(-1765 860);
DISPLAY 0.659574 (-1765 860);
PAINT MONO (-1765 860);
DISPLAY INVISIBLE (-1765 860);
FORCEPROP 1 LAST HDL_POWER P3V3_STBY
J 1
(-1775 950);
DISPLAY 0.489362 (-1775 950);
PAINT GREEN (-1775 950);
FORCEPROP 1 LAST PATH I20
J 0
(-1725 925);
DISPLAY 0.872340 (-1725 925);
PAINT AQUA (-1725 925);
DISPLAY INVISIBLE (-1725 925);
FORCEPROP 2 LAST CDS_LIB pure_quanta_power
J 0
(-1775 900);
DISPLAY INVISIBLE (-1775 900);
FORCEADD Q_RES..1
R 1
(-1575 -25);
FORCEPROP 1 LAST LOCATION R3
J 0
(-1525 100);
DISPLAY 0.489362 (-1525 100);
PAINT SKYBLUE (-1525 100);
FORCEPROP 0 LAST $SEC 1
R 1
J 0
(-1525 125);
DISPLAY 0.680851 (-1525 125);
PAINT MONO (-1525 125);
DISPLAY INVISIBLE (-1525 125);
FORCEPROP 0 LAST CDS_SEC 1
R 1
J 0
(-1525 125);
DISPLAY 1.021277 (-1525 125);
DISPLAY INVISIBLE (-1525 125);
FORCEPROP 1 LASTPIN (-1575 -125) $PN 1
J 0
(-1610 -90);
DISPLAY 0.489362 (-1610 -90);
PAINT MONO (-1610 -90);
FORCEPROP 1 LASTPIN (-1575 75) $PN 2
J 0
(-1610 35);
DISPLAY 0.489362 (-1610 35);
PAINT MONO (-1610 35);
FORCEPROP 1 LAST PACK_TYPE 0402LF
J 0
(-1525 -200);
DISPLAY 0.489362 (-1525 -200);
PAINT SKYBLUE (-1525 -200);
FORCEPROP 1 LAST PART_NUMBER CS31502FB05
J 0
(-1525 -150);
DISPLAY 0.489362 (-1525 -150);
PAINT SKYBLUE (-1525 -150);
FORCEPROP 1 LAST VALUE 15K
J 2
(-1450 50);
DISPLAY 0.489362 (-1450 50);
PAINT SKYBLUE (-1450 50);
FORCEPROP 1 LAST TOLERANCE 1%
J 0
(-1525 0);
DISPLAY 0.489362 (-1525 0);
PAINT SKYBLUE (-1525 0);
FORCEPROP 1 LAST MATERIAL CHIP
J 0
(-1525 -100);
DISPLAY 0.489362 (-1525 -100);
PAINT SKYBLUE (-1525 -100);
FORCEPROP 1 LAST WATTAGE 1/16W
J 2
(-1400 -50);
DISPLAY 0.489362 (-1400 -50);
PAINT SKYBLUE (-1400 -50);
FORCEPROP 1 LAST PATH I21
R 1
J 0
(-1725 -75);
DISPLAY 0.978723 (-1725 -75);
PAINT WHITE (-1725 -75);
DISPLAY INVISIBLE (-1725 -75);
FORCEPROP 2 LAST CDS_LIB pure_quanta
R 1
J 0
(-1575 -25);
DISPLAY INVISIBLE (-1575 -25);
FORCEADD Q_RES..1
R 1
(-1575 -425);
FORCEPROP 1 LAST LOCATION R4
J 0
(-1525 -325);
DISPLAY 0.489362 (-1525 -325);
PAINT SKYBLUE (-1525 -325);
FORCEPROP 0 LAST $SEC 1
R 1
J 0
(-1525 -300);
DISPLAY 0.680851 (-1525 -300);
PAINT MONO (-1525 -300);
DISPLAY INVISIBLE (-1525 -300);
FORCEPROP 0 LAST CDS_SEC 1
R 1
J 0
(-1525 -300);
DISPLAY 1.021277 (-1525 -300);
DISPLAY INVISIBLE (-1525 -300);
FORCEPROP 1 LASTPIN (-1575 -525) $PN 1
J 0
(-1610 -490);
DISPLAY 0.489362 (-1610 -490);
PAINT MONO (-1610 -490);
FORCEPROP 1 LASTPIN (-1575 -325) $PN 2
J 0
(-1610 -365);
DISPLAY 0.489362 (-1610 -365);
PAINT MONO (-1610 -365);
FORCEPROP 1 LAST PACK_TYPE 0402LF
J 0
(-1525 -625);
DISPLAY 0.489362 (-1525 -625);
PAINT SKYBLUE (-1525 -625);
FORCEPROP 1 LAST PART_NUMBER CS31202FB04
J 0
(-1525 -575);
DISPLAY 0.489362 (-1525 -575);
PAINT SKYBLUE (-1525 -575);
FORCEPROP 1 LAST VALUE 12K
J 2
(-1450 -375);
DISPLAY 0.489362 (-1450 -375);
PAINT SKYBLUE (-1450 -375);
FORCEPROP 1 LAST TOLERANCE 1%
J 0
(-1525 -425);
DISPLAY 0.489362 (-1525 -425);
PAINT SKYBLUE (-1525 -425);
FORCEPROP 1 LAST MATERIAL CHIP
J 0
(-1525 -525);
DISPLAY 0.489362 (-1525 -525);
PAINT SKYBLUE (-1525 -525);
FORCEPROP 1 LAST WATTAGE 1/16W
J 2
(-1400 -475);
DISPLAY 0.489362 (-1400 -475);
PAINT SKYBLUE (-1400 -475);
FORCEPROP 1 LAST PATH I22
R 1
J 0
(-1725 -475);
DISPLAY 0.978723 (-1725 -475);
PAINT WHITE (-1725 -475);
DISPLAY INVISIBLE (-1725 -475);
FORCEPROP 2 LAST CDS_LIB pure_quanta
R 1
J 0
(-1575 -425);
DISPLAY INVISIBLE (-1575 -425);
FORCEADD UNIVERSAL_GND..1
(-4775 -275);
FORCEPROP 3 LASTPIN (-4775 -225) SIG_NAME GND\g
J 0
(-4765 -215);
DISPLAY 0.659574 (-4765 -215);
PAINT MONO (-4765 -215);
DISPLAY INVISIBLE (-4765 -215);
FORCEPROP 1 LAST HDL_POWER GND
J 1
(-4750 -350);
DISPLAY 0.872340 (-4750 -350);
PAINT GREEN (-4750 -350);
DISPLAY INVISIBLE (-4750 -350);
FORCEPROP 1 LAST PATH I23
J 0
(-4700 -275);
DISPLAY 0.872340 (-4700 -275);
PAINT AQUA (-4700 -275);
DISPLAY INVISIBLE (-4700 -275);
FORCEPROP 2 LAST CDS_LIB pure_quanta_power
J 0
(-4775 -275);
DISPLAY INVISIBLE (-4775 -275);
FORCEADD Q_CAP..1
R 2
(-4775 -75);
FORCEPROP 1 LAST LOCATION C345
J 2
(-4825 25);
DISPLAY 0.489362 (-4825 25);
PAINT SKYBLUE (-4825 25);
FORCEPROP 0 LAST $SEC 1
J 0
(-4825 75);
DISPLAY 0.680851 (-4825 75);
PAINT MONO (-4825 75);
DISPLAY INVISIBLE (-4825 75);
FORCEPROP 0 LAST CDS_SEC 1
J 0
(-4825 75);
DISPLAY 0.680851 (-4825 75);
DISPLAY INVISIBLE (-4825 75);
FORCEPROP 1 LASTPIN (-4775 25) $PN 1
J 2
(-4785 5);
DISPLAY 0.489362 (-4785 5);
PAINT MONO (-4785 5);
FORCEPROP 1 LASTPIN (-4775 -175) $PN 2
J 2
(-4785 -195);
DISPLAY 0.489362 (-4785 -195);
PAINT MONO (-4785 -195);
FORCEPROP 1 LAST TOLERANCE 10%
J 2
(-4825 -125);
DISPLAY 0.489362 (-4825 -125);
PAINT SKYBLUE (-4825 -125);
FORCEPROP 1 LAST MATERIAL EMPTY
J 2
(-4825 -175);
DISPLAY 0.489362 (-4825 -175);
PAINT RED (-4825 -175);
FORCEPROP 1 LAST PART_NUMBER CH4104K1B00
J 2
(-4850 -225);
DISPLAY 0.489362 (-4850 -225);
PAINT SKYBLUE (-4850 -225);
FORCEPROP 1 LAST PACK_TYPE 0402
J 2
(-4825 -275);
DISPLAY 0.489362 (-4825 -275);
PAINT SKYBLUE (-4825 -275);
FORCEPROP 1 LAST VOLTAGE 25V
J 2
(-4825 -75);
DISPLAY 0.489362 (-4825 -75);
PAINT SKYBLUE (-4825 -75);
FORCEPROP 1 LAST VALUE 0.1UF
J 2
(-4825 -25);
DISPLAY 0.489362 (-4825 -25);
PAINT SKYBLUE (-4825 -25);
FORCEPROP 2 LAST ROOM VR_DDR0_CTRL
R 3
J 1
(-4831 -114);
DISPLAY 0.744681 (-4831 -114);
PAINT RED (-4831 -114);
DISPLAY INVISIBLE (-4831 -114);
FORCEPROP 1 LAST PATH I24
J 2
(-4825 75);
DISPLAY 0.978723 (-4825 75);
PAINT WHITE (-4825 75);
DISPLAY INVISIBLE (-4825 75);
FORCEPROP 2 LAST CDS_LIB pure_quanta
J 0
(-4775 -75);
DISPLAY INVISIBLE (-4775 -75);
FORCEADD Q_RES..1
(-4325 -450);
FORCEPROP 1 LAST LOCATION R214
J 0
(-4200 -450);
DISPLAY 0.489362 (-4200 -450);
PAINT SKYBLUE (-4200 -450);
FORCEPROP 0 LAST $SEC 1
J 2
(-4200 -400);
DISPLAY 0.680851 (-4200 -400);
PAINT MONO (-4200 -400);
DISPLAY INVISIBLE (-4200 -400);
FORCEPROP 0 LAST CDS_SEC 1
J 2
(-4200 -400);
DISPLAY 1.021277 (-4200 -400);
DISPLAY INVISIBLE (-4200 -400);
FORCEPROP 1 LASTPIN (-4425 -450) $PN 1
J 0
(-4413 -438);
DISPLAY 0.489362 (-4413 -438);
PAINT MONO (-4413 -438);
FORCEPROP 1 LASTPIN (-4225 -450) $PN 2
J 0
(-4263 -438);
DISPLAY 0.489362 (-4263 -438);
PAINT MONO (-4263 -438);
FORCEPROP 1 LAST VALUE 33
J 2
(-4450 -450);
DISPLAY 0.489362 (-4450 -450);
PAINT SKYBLUE (-4450 -450);
FORCEPROP 2 LAST ROOM RST_CPU0_PLD_TO_DIMM
J 2
(-4300 -350);
DISPLAY 0.744681 (-4300 -350);
PAINT RED (-4300 -350);
DISPLAY INVISIBLE (-4300 -350);
FORCEPROP 1 LAST PACK_TYPE 0402LF
J 2
(-4150 -525);
DISPLAY 0.489362 (-4150 -525);
PAINT SKYBLUE (-4150 -525);
DISPLAY INVISIBLE (-4150 -525);
FORCEPROP 1 LAST PART_NUMBER CS03302JB29
J 2
(-4225 -400);
DISPLAY 0.489362 (-4225 -400);
PAINT SKYBLUE (-4225 -400);
DISPLAY INVISIBLE (-4225 -400);
FORCEPROP 1 LAST TOLERANCE 5%
J 0
(-4450 -475);
DISPLAY 0.489362 (-4450 -475);
PAINT SKYBLUE (-4450 -475);
DISPLAY INVISIBLE (-4450 -475);
FORCEPROP 1 LAST MATERIAL CHIP
J 2
(-4150 -475);
DISPLAY 0.489362 (-4150 -475);
PAINT SKYBLUE (-4150 -475);
DISPLAY INVISIBLE (-4150 -475);
FORCEPROP 1 LAST WATTAGE 1/16W
J 2
(-4400 -525);
DISPLAY 0.489362 (-4400 -525);
PAINT SKYBLUE (-4400 -525);
DISPLAY INVISIBLE (-4400 -525);
FORCEPROP 1 LAST PATH I25
J 0
(-4375 -300);
DISPLAY 0.978723 (-4375 -300);
PAINT WHITE (-4375 -300);
DISPLAY INVISIBLE (-4375 -300);
FORCEPROP 2 LAST CDS_LIB pure_quanta
J 2
(-4325 -450);
DISPLAY INVISIBLE (-4325 -450);
FORCEPROP 2 LAST BOM_COST MEM
J 2
(-4300 -300);
DISPLAY 0.744681 (-4300 -300);
PAINT WHITE (-4300 -300);
DISPLAY INVISIBLE (-4300 -300);
FORCEADD OFFPAGE..2
R 2
(-5175 -450);
FORCEPROP 2 LAST $XR0 80 
J 0
(-5429 -450);
DISPLAY 0.638298 (-5429 -450);
PAINT MONO (-5429 -450);
FORCEPROP 2 LAST PATH I26
J 0
(-5425 -400);
DISPLAY 0.680851 (-5425 -400);
DISPLAY INVISIBLE (-5425 -400);
FORCEPROP 1 LAST COMMENT_BODY TRUE
J 2
(-5130 -545);
DISPLAY 0.872340 (-5130 -545);
PAINT GREEN (-5130 -545);
DISPLAY INVISIBLE (-5130 -545);
FORCEPROP 1 LAST OFFPAGE TRUE
J 2
(-5500 -575);
DISPLAY 0.872340 (-5500 -575);
PAINT GREEN (-5500 -575);
DISPLAY INVISIBLE (-5500 -575);
FORCEPROP 2 LAST CDS_LIB standard
J 0
(-5175 -450);
DISPLAY INVISIBLE (-5175 -450);
FORCEADD VCC_CORE..1
(-3875 -200);
FORCEPROP 3 LASTPIN (-3875 -250) SIG_NAME P3V3_STBY\g
J 0
(-3865 -240);
DISPLAY 0.659574 (-3865 -240);
PAINT MONO (-3865 -240);
DISPLAY INVISIBLE (-3865 -240);
FORCEPROP 1 LAST HDL_POWER P3V3_STBY
J 1
(-3875 -150);
DISPLAY 0.489362 (-3875 -150);
PAINT GREEN (-3875 -150);
FORCEPROP 1 LAST PATH I3
J 0
(-3825 -175);
DISPLAY 0.872340 (-3825 -175);
PAINT AQUA (-3825 -175);
DISPLAY INVISIBLE (-3825 -175);
FORCEPROP 2 LAST CDS_LIB pure_quanta_power
J 0
(-3875 -200);
DISPLAY INVISIBLE (-3875 -200);
FORCEADD RT9059GQW..1
(-2625 50);
FORCEPROP 1 LAST LOCATION U1
J 0
(-2875 750);
DISPLAY 0.489362 (-2875 750);
PAINT SKYBLUE (-2875 750);
FORCEPROP 0 LAST $SEC 1
J 0
(-2875 900);
DISPLAY 0.680851 (-2875 900);
PAINT MONO (-2875 900);
DISPLAY INVISIBLE (-2875 900);
FORCEPROP 0 LAST CDS_SEC 1
J 0
(-2875 900);
DISPLAY 1.021277 (-2875 900);
DISPLAY INVISIBLE (-2875 900);
FORCEPROP 0 LASTPIN (-2225 -250) $PN 4
J 0
(-2215 -240);
DISPLAY 0.489362 (-2215 -240);
PAINT MONO (-2215 -240);
FORCEPROP 0 LASTPIN (-3025 100) $PN 6
J 2
(-3035 110);
DISPLAY 0.489362 (-3035 110);
PAINT MONO (-3035 110);
FORCEPROP 0 LASTPIN (-2225 -450) $PN TH
J 0
(-2215 -440);
DISPLAY 0.489362 (-2215 -440);
PAINT MONO (-2215 -440);
FORCEPROP 0 LASTPIN (-3025 -450) $PN 5
J 2
(-3035 -440);
DISPLAY 0.489362 (-3035 -440);
PAINT MONO (-3035 -440);
FORCEPROP 0 LASTPIN (-3025 550) $PN 10
J 2
(-3035 560);
DISPLAY 0.489362 (-3035 560);
PAINT MONO (-3035 560);
FORCEPROP 0 LASTPIN (-2225 550) $PN 7
J 0
(-2215 560);
DISPLAY 0.489362 (-2215 560);
PAINT MONO (-2215 560);
FORCEPROP 0 LASTPIN (-2225 500) $PN 8
J 0
(-2215 510);
DISPLAY 0.489362 (-2215 510);
PAINT MONO (-2215 510);
FORCEPROP 0 LASTPIN (-2225 450) $PN 9
J 0
(-2215 460);
DISPLAY 0.489362 (-2215 460);
PAINT MONO (-2215 460);
FORCEPROP 0 LASTPIN (-2225 150) $PN 1
J 0
(-2215 160);
DISPLAY 0.489362 (-2215 160);
PAINT MONO (-2215 160);
FORCEPROP 0 LASTPIN (-2225 100) $PN 2
J 0
(-2215 110);
DISPLAY 0.489362 (-2215 110);
PAINT MONO (-2215 110);
FORCEPROP 0 LASTPIN (-2225 50) $PN 3
J 0
(-2215 60);
DISPLAY 0.489362 (-2215 60);
PAINT MONO (-2215 60);
FORCEPROP 2 LAST VALUE RT9059GQW
J 0
(-2875 800);
DISPLAY 0.489362 (-2875 800);
PAINT SKYBLUE (-2875 800);
FORCEPROP 1 LAST PART_NUMBER AL009059000
J 0
(-2875 685);
DISPLAY 0.489362 (-2875 685);
PAINT SKYBLUE (-2875 685);
FORCEPROP 1 LAST MATERIAL IC
J 0
(-2875 615);
DISPLAY 0.489362 (-2875 615);
PAINT SKYBLUE (-2875 615);
FORCEPROP 2 LAST PART_TYPE SMLF
J 0
(-2875 850);
DISPLAY 1.021277 (-2875 850);
FORCEPROP 1 LAST PATH I4
J 2
(-2375 -500);
DISPLAY 0.723404 (-2375 -500);
PAINT GREEN (-2375 -500);
DISPLAY INVISIBLE (-2375 -500);
FORCEPROP 1 LAST CDS_LMAN_SYM_OUTLINE -250,550,250,-550
J 0
(-2625 50);
DISPLAY 0.468085 (-2625 50);
PAINT GREEN (-2625 50);
DISPLAY INVISIBLE (-2625 50);
FORCEPROP 2 LAST CDS_LIB pure_quanta
J 0
(-2625 50);
DISPLAY INVISIBLE (-2625 50);
FORCEPROP 1 LAST PIN_NAMES_ROTATE TRUE
J 0
(-2625 50);
DISPLAY 0.723404 (-2625 50);
PAINT GREEN (-2625 50);
DISPLAY INVISIBLE (-2625 50);
FORCEADD Q_RES..1
(-3475 -325);
FORCEPROP 1 LAST LOCATION R2
J 0
(-3525 -275);
DISPLAY 0.489362 (-3525 -275);
PAINT SKYBLUE (-3525 -275);
FORCEPROP 0 LAST $SEC 1
J 0
(-3325 -250);
DISPLAY 0.680851 (-3325 -250);
PAINT MONO (-3325 -250);
DISPLAY INVISIBLE (-3325 -250);
FORCEPROP 0 LAST CDS_SEC 1
J 0
(-3325 -250);
DISPLAY 1.021277 (-3325 -250);
DISPLAY INVISIBLE (-3325 -250);
FORCEPROP 1 LASTPIN (-3575 -325) $PN 1
J 0
(-3563 -313);
DISPLAY 0.489362 (-3563 -313);
PAINT MONO (-3563 -313);
FORCEPROP 1 LASTPIN (-3375 -325) $PN 2
J 0
(-3413 -313);
DISPLAY 0.489362 (-3413 -313);
PAINT MONO (-3413 -313);
FORCEPROP 1 LAST VALUE 10K
J 2
(-3650 -275);
DISPLAY 0.489362 (-3650 -275);
PAINT SKYBLUE (-3650 -275);
FORCEPROP 1 LAST TOLERANCE 5%
J 0
(-3325 -275);
DISPLAY 0.489362 (-3325 -275);
PAINT SKYBLUE (-3325 -275);
FORCEPROP 1 LAST PACK_TYPE 0402LF
J 0
(-3375 -375);
DISPLAY 0.489362 (-3375 -375);
PAINT SKYBLUE (-3375 -375);
FORCEPROP 1 LAST WATTAGE 1/16W
J 0
(-3375 -400);
DISPLAY 0.489362 (-3375 -400);
PAINT SKYBLUE (-3375 -400);
FORCEPROP 1 LAST PART_NUMBER TMP_QCS31002JB28
J 0
(-3850 -375);
DISPLAY 0.489362 (-3850 -375);
PAINT SKYBLUE (-3850 -375);
FORCEPROP 1 LAST MATERIAL CHIP
J 0
(-3850 -400);
DISPLAY 0.489362 (-3850 -400);
PAINT SKYBLUE (-3850 -400);
FORCEPROP 1 LAST PATH I6
J 0
(-3525 -175);
DISPLAY 0.978723 (-3525 -175);
PAINT WHITE (-3525 -175);
DISPLAY INVISIBLE (-3525 -175);
FORCEPROP 2 LAST CDS_LIB pure_quanta
J 0
(-3475 -325);
DISPLAY INVISIBLE (-3475 -325);
FORCEADD UNIVERSAL_GND..1
(-3400 200);
FORCEPROP 3 LASTPIN (-3400 250) SIG_NAME GND\g
J 0
(-3390 260);
DISPLAY 0.659574 (-3390 260);
PAINT MONO (-3390 260);
DISPLAY INVISIBLE (-3390 260);
FORCEPROP 1 LAST HDL_POWER GND
J 1
(-3375 125);
DISPLAY 0.872340 (-3375 125);
PAINT GREEN (-3375 125);
DISPLAY INVISIBLE (-3375 125);
FORCEPROP 1 LAST PATH I7
J 0
(-3325 200);
DISPLAY 0.872340 (-3325 200);
PAINT AQUA (-3325 200);
DISPLAY INVISIBLE (-3325 200);
FORCEPROP 2 LAST CDS_LIB pure_quanta_power
J 0
(-3400 200);
DISPLAY INVISIBLE (-3400 200);
FORCEADD Q_CAP..1
(-3400 400);
FORCEPROP 1 LAST LOCATION C1
J 0
(-3350 500);
DISPLAY 0.489362 (-3350 500);
PAINT SKYBLUE (-3350 500);
FORCEPROP 0 LAST $SEC 1
J 0
(-3350 525);
DISPLAY 0.680851 (-3350 525);
PAINT MONO (-3350 525);
DISPLAY INVISIBLE (-3350 525);
FORCEPROP 0 LAST CDS_SEC 1
J 0
(-3350 525);
DISPLAY 1.021277 (-3350 525);
DISPLAY INVISIBLE (-3350 525);
FORCEPROP 1 LASTPIN (-3400 500) $PN 1
J 0
(-3390 480);
DISPLAY 0.489362 (-3390 480);
PAINT MONO (-3390 480);
FORCEPROP 1 LASTPIN (-3400 300) $PN 2
J 0
(-3390 280);
DISPLAY 0.489362 (-3390 280);
PAINT MONO (-3390 280);
FORCEPROP 1 LAST VALUE 1UF
J 0
(-3350 450);
DISPLAY 0.489362 (-3350 450);
PAINT SKYBLUE (-3350 450);
FORCEPROP 1 LAST PART_NUMBER CH5104KEB02
J 0
(-3350 250);
DISPLAY 0.489362 (-3350 250);
PAINT SKYBLUE (-3350 250);
FORCEPROP 1 LAST MATERIAL X6S
J 0
(-3350 300);
DISPLAY 0.489362 (-3350 300);
PAINT SKYBLUE (-3350 300);
FORCEPROP 1 LAST PACK_TYPE C0402
J 0
(-3350 200);
DISPLAY 0.489362 (-3350 200);
PAINT SKYBLUE (-3350 200);
FORCEPROP 1 LAST VOLTAGE 25V
J 0
(-3350 400);
DISPLAY 0.489362 (-3350 400);
PAINT SKYBLUE (-3350 400);
FORCEPROP 1 LAST TOLERANCE 10%
J 0
(-3350 350);
DISPLAY 0.489362 (-3350 350);
PAINT SKYBLUE (-3350 350);
FORCEPROP 1 LAST PATH I8
J 0
(-3350 550);
DISPLAY 0.978723 (-3350 550);
PAINT WHITE (-3350 550);
DISPLAY INVISIBLE (-3350 550);
FORCEPROP 2 LAST CDS_LIB pure_quanta
J 0
(-3400 400);
DISPLAY INVISIBLE (-3400 400);
FORCEADD VCC_CORE..1
(-3400 675);
FORCEPROP 3 LASTPIN (-3400 625) SIG_NAME P5V_STBY\g
J 0
(-3390 635);
DISPLAY 0.659574 (-3390 635);
PAINT MONO (-3390 635);
DISPLAY INVISIBLE (-3390 635);
FORCEPROP 1 LAST HDL_POWER P5V_STBY
J 1
(-3400 725);
DISPLAY 0.489362 (-3400 725);
PAINT GREEN (-3400 725);
FORCEPROP 1 LAST PATH I9
J 0
(-3350 700);
DISPLAY 0.872340 (-3350 700);
PAINT AQUA (-3350 700);
DISPLAY INVISIBLE (-3350 700);
FORCEPROP 2 LAST CDS_LIB pure_quanta_power
J 0
(-3400 675);
DISPLAY INVISIBLE (-3400 675);
FORCEADD DNS..1
(-4800 -175);
PAINT RED (-4800 -175);
FORCEPROP 1 LAST COMMENT_BODY TRUE
J 0
(-4800 -175);
DISPLAY INVISIBLE (-4800 -175);
FORCEPROP 2 LAST CDS_LIB mstr_misc
J 0
(-4800 -175);
DISPLAY INVISIBLE (-4800 -175);
FORCEADD QUANTA_TITLE_BLOCK_C..1
(2425 -3300);
FORCEPROP 0 LAST CDS_CON_LAST_MODIFIED Fri Mar 11 14:53:22 2022
J 0
(540 -3285);
DISPLAY INVISIBLE (540 -3285);
FORCEPROP 1 LAST CUSTOM_TXT_CDS <CON_LAST_MODIFIED>
J 0
(540 -3285);
DISPLAY 0.978723 (540 -3285);
FORCEPROP 2 LAST CUSTOM_TXT_CDS <XR_PAGE_TITLE>
J 0
(-5465 1950);
DISPLAY 0.638298 (-5465 1950);
PAINT PINK (-5465 1950);
DISPLAY INVISIBLE (-5465 1950);
FORCEPROP 1 LAST CUSTOM_TXT_CDS <NAME_2>
J 0
(-750 -3250);
FORCEPROP 1 LAST CUSTOM_TXT_CDS <NAME_1>
J 0
(-750 -3125);
FORCEPROP 1 LAST CUSTOM_TXT_CDS <Q_NUMBER>
J 0
(1022 -3197);
DISPLAY 1.212766 (1022 -3197);
FORCEPROP 1 LAST CUSTOM_TXT_CDS <Q_PROJ>
J 0
(43 -3198);
DISPLAY 1.212766 (43 -3198);
FORCEPROP 1 LAST CUSTOM_TXT_CDS <Q_REV>
J 0
(2241 -3197);
DISPLAY 1.212766 (2241 -3197);
FORCEPROP 1 LAST CUSTOM_TXT_CDS <CON_PAGE_NUM> OF <CON_TOTAL_PAGES>
J 0
(1979 -3282);
DISPLAY 0.978723 (1979 -3282);
FORCEPROP 1 LAST Q_DEPT BU9
J 1
(-1338 -3251);
DISPLAY 1.957447 (-1338 -3251);
PAINT GREEN (-1338 -3251);
FORCEPROP 1 LAST Q_TITLE P1V8_STBY
J 0
(-6850 -3225);
DISPLAY 2.446809 (-6850 -3225);
PAINT GREEN (-6850 -3225);
FORCEPROP 1 LAST COMMENT_BODY TRUE
J 0
(2437 -3313);
DISPLAY 0.978723 (2437 -3313);
PAINT GREEN (2437 -3313);
DISPLAY INVISIBLE (2437 -3313);
FORCEPROP 2 LAST PAGE_BORDER TRUE
J 0
(-5465 1950);
DISPLAY 0.638298 (-5465 1950);
PAINT PINK (-5465 1950);
DISPLAY INVISIBLE (-5465 1950);
FORCEPROP 1 LAST CDS_LMAN_SYM_OUTLINE -9475,6775,100,-125
J 0
(2425 -3300);
DISPLAY 0.468085 (2425 -3300);
PAINT GREEN (2425 -3300);
DISPLAY INVISIBLE (2425 -3300);
FORCEPROP 2 LAST CDS_LIB pure_quanta
J 0
(2425 -3300);
DISPLAY INVISIBLE (2425 -3300);
FORCEPROP 2 LAST CDS_XR_PAGE_TITLE CR-167 : @T6G_MB_LIB.T6G(SCH_1):PAGE167
J 0
(-5465 1950);
DISPLAY 0.638298 (-5465 1950);
PAINT PINK (-5465 1950);
DISPLAY INVISIBLE (-5465 1950);
WIRE 16 -1 (-1575 -525)(-1575 -600);
WIRE 16 -1 (-1775 475)(-1775 400);
WIRE 16 -1 (-4775 -225)(-4775 -175);
WIRE 16 -1 (-3400 300)(-3400 250);
WIRE 16 -1 (-1975 -600)(-1975 -450);
WIRE 16 -1 (-1975 -450)(-2225 -450);
WIRE 16 -1 (-475 -125)(-475 -275);
WIRE 16 -1 (-475 -275)(-475 -350);
WIRE 16 -1 (-850 -275)(-475 -275);
WIRE 16 -1 (-850 -125)(-850 -275);
WIRE 16 -1 (-2100 100)(-2100 50);
WIRE 16 -1 (-2225 100)(-2100 100);
WIRE 16 -1 (-2100 150)(-2100 100);
WIRE 16 -1 (-2100 50)(-2225 50);
WIRE 16 -1 (-1575 150)(-2100 150);
WIRE 16 -1 (-2100 150)(-2225 150);
WIRE 16 -1 (-1575 150)(-850 150);
WIRE 16 -1 (-1575 75)(-1575 150);
WIRE 16 -1 (-850 150)(-475 150);
WIRE 16 -1 (-850 75)(-850 150);
WIRE 16 -1 (-475 200)(-475 150);
WIRE 16 -1 (-475 150)(-475 75);
WIRE 16 -1 (-2050 450)(-2225 450);
WIRE 16 -1 (-2050 500)(-2050 450);
WIRE 16 -1 (-2050 550)(-2050 500);
WIRE 16 -1 (-2225 500)(-2050 500);
WIRE 16 -1 (-2225 550)(-2050 550);
WIRE 16 -1 (-2050 750)(-2050 550);
WIRE 16 -1 (-1775 750)(-2050 750);
WIRE 16 -1 (-1775 850)(-1775 750);
WIRE 16 -1 (-1775 675)(-1775 750);
WIRE 16 -1 (-3875 -250)(-3875 -325);
WIRE 16 -1 (-3875 -325)(-3575 -325);
WIRE 16 -1 (-3400 500)(-3400 550);
WIRE 16 -1 (-3400 550)(-3025 550);
WIRE 16 -1 (-3400 625)(-3400 550);
WIRE 16 -1 (-4775 100)(-3025 100);
WIRE 16 -1 (-4775 100)(-4775 25);
WIRE 16 -1 (-5300 100)(-4775 100);
FORCEPROP 2 LAST SIG_NAME PWRGD_P3V3_STBY_R
J 0
(-5260 110);
DISPLAY 0.489362 (-5260 110);
WIRE 16 -1 (-3200 -450)(-3200 -325);
WIRE 16 -1 (-3025 -450)(-3200 -450);
WIRE 16 -1 (-3200 -450)(-4225 -450);
FORCEPROP 2 LAST SIG_NAME PWRGD_P1V8_STBY
J 0
(-3900 -440);
DISPLAY 0.489362 (-3900 -440);
FORCEPROP 2 LASTPROP $XRERR UNIQUE?
J 0
(-4140 -440);
DISPLAY 0.638298 (-4140 -440);
PAINT MONO (-4140 -440);
DISPLAY INVISIBLE (-4140 -440);
WIRE 16 -1 (-3200 -325)(-3375 -325);
WIRE 16 -1 (-5125 -450)(-4425 -450);
FORCEPROP 2 LAST SIG_NAME PWRGD_P1V8_STBY_R
J 0
(-4950 -450);
DISPLAY 0.489362 (-4950 -450);
WIRE 17 273 (-6700 -2625)(-4525 -2625);
WIRE 17 273 (-6700 -2225)(-6700 -2625);
WIRE 17 273 (-4525 -2225)(-4525 -2625);
WIRE 17 273 (-6700 -2225)(-4525 -2225);
WIRE 16 -1 (-1575 -250)(-1575 -125);
WIRE 16 -1 (-1575 -250)(-1575 -325);
WIRE 16 -1 (-2225 -250)(-1575 -250);
FORCEPROP 2 LAST SIG_NAME P1V8_STBY_ADJ
J 2
(-1885 -240);
DISPLAY 0.489362 (-1885 -240);
FORCEPROP 2 LASTPROP $XRERR UNIQUE?
J 0
(-2125 -240);
DISPLAY 0.638298 (-2125 -240);
PAINT MONO (-2125 -240);
DISPLAY INVISIBLE (-2125 -240);
WIRE 17 273 (525 2600)(2300 2600);
WIRE 17 273 (525 3275)(525 2600);
WIRE 17 273 (2300 3275)(2300 2600);
WIRE 17 273 (525 3275)(2300 3275);
DOT 1 (-2050 550);
DOT 1 (-2100 150);
DOT 1 (-475 150);
DOT 1 (-850 150);
DOT 1 (-1775 750);
DOT 1 (-1575 150);
DOT 1 (-2050 500);
DOT 1 (-2100 100);
DOT 1 (-3400 550);
DOT 1 (-475 -275);
DOT 1 (-1575 -250);
DOT 1 (-4775 100);
DOT 1 (-3200 -450);
FORCENOTE
VOUT=0.8(1+RA/RB)=1.8V
(-1200 -800) 0;
DISPLAY LEFT (-1200 -800);
DISPLAY 1.021277 (-1200 -800);
PAINT WHITE (-1200 -800);
FORCENOTE
P1V8_STBY SPECIFICATION
(575 3150) 0;
DISPLAY LEFT (575 3150);
DISPLAY 1.595745 (575 3150);
PAINT WHITE (575 3150);
FORCENOTE
IMAX = 0.252A
(575 2800) 0;
DISPLAY LEFT (575 2800);
DISPLAY 1.021277 (575 2800);
PAINT WHITE (575 2800);
FORCENOTE
TDC = 0.21A
(575 2875) 0;
DISPLAY LEFT (575 2875);
DISPLAY 1.021277 (575 2875);
PAINT WHITE (575 2875);
FORCENOTE
OCP = 3.1A(FIX)
(575 2725) 0;
DISPLAY LEFT (575 2725);
DISPLAY 1.021277 (575 2725);
PAINT WHITE (575 2725);
FORCENOTE
PD=(3.3V-1.5V)*0.21A=0.378W
(575 2650) 0;
DISPLAY LEFT (575 2650);
DISPLAY 1.021277 (575 2650);
PAINT WHITE (575 2650);
FORCENOTE
RIPPLE = +/- 15MV
(575 2950) 0;
DISPLAY LEFT (575 2950);
DISPLAY 1.021277 (575 2950);
PAINT WHITE (575 2950);
FORCENOTE
OUTPUT VOLTAGE = 1.8V
(575 3025) 0;
DISPLAY LEFT (575 3025);
DISPLAY 1.021277 (575 3025);
PAINT WHITE (575 3025);
FORCENOTE
MAIN SOURCE:AL009059000/RT9059GQW
(-6650 -2475) 0;
DISPLAY LEFT (-6650 -2475);
DISPLAY 1.021277 (-6650 -2475);
PAINT WHITE (-6650 -2475);
FORCENOTE
2ND SOURCE:AL009661002/G9661-25ADJRE1U
(-6650 -2575) 0;
DISPLAY LEFT (-6650 -2575);
DISPLAY 1.021277 (-6650 -2575);
PAINT WHITE (-6650 -2575);
FORCENOTE
BOM NOTE
(-6650 -2325) 0;
DISPLAY LEFT (-6650 -2325);
DISPLAY 1.276596 (-6650 -2325);
PAINT WHITE (-6650 -2325);
FORCENOTE
P1V8_STBY
(-3525 1725) 0;
DISPLAY LEFT (-3525 1725);
DISPLAY 3.936170 (-3525 1725);
PAINT WHITE (-3525 1725);
QUIT
